# BASEBOARD_FAB2 (Tioga Pass) — schematic netlist excerpt (pin names and nets, part order shuffled) for the footprints in the layout excerpt that follows; sources: Cadence DE-HDL packaged netlist, KiCad conversion of Wiwynn_Tioga_Pass_MB.brd

J8E4  SCONN64_H87568002_A  CONN  pkg SMT  page 188
  IO1  = SMB_OCP_FRU_STBY_LVC3_SCL
  IO2  = SMB_OCP_FRU_STBY_LVC3_SDA
  IO3  = EXT_MDIO_I2C_SEL
  IO4  = GND
  IO5  = NC
  IO6  = NC
  IO7  = GND
  IO8  = LED_GBE_P1_0
  IO9  = LED_GBE_P1_1
  IO10  = GND
  IO11  = NC
  IO12  = NC
  IO13  = GND
  IO14  = LED_GBE_P2_0
  IO15  = LED_GBE_P2_1
  IO16  = GND
  IO17  = NC
  IO18  = NC
  IO19  = GND
  IO20  = SMB_PCH_MEZZ_LOM0_SCL
  IO21  = SMB_PCH_MEZZ_LOM0_SDA
  IO22  = GND
  IO23  = NC
  IO24  = NC
  IO25  = GND
  IO26  = SMB_PCH_MEZZ_LOM1_SCL
  IO27  = SMB_PCH_MEZZ_LOM1_SDA
  IO28  = GND
  IO29  = SMB_PCH_MEZZ_LOM3_SCL
  IO30  = SMB_PCH_MEZZ_LOM3_SDA
  IO31  = FM_GBE2_LVC3_MOD_ABS
  IO32  = FM_GBE3_LVC3_MOD_ABS
  IO33  = P12V_STBY
  IO34  = P12V_STBY
  IO35  = P12V_STBY
  IO36  = TP_RSVD<0>
  IO37  = FM_GBE0_LVC3_MOD_ABS
  IO38  = FM_GBE1_LVC3_MOD_ABS
  IO39  = GND
  IO40  = KR_P0_OCP_TX_DP
  IO41  = KR_P0_OCP_TX_DN
  IO42  = GND
  IO43  = LED_GBE_P0_0
  IO44  = LED_GBE_P0_1
  IO45  = GND
  IO46  = KR_P1_OCP_TX_DP
  IO47  = KR_P1_OCP_TX_DN
  IO48  = GND
  IO49  = TP_SHARED_KR_MDC_0
  IO50  = TP_SHARED_KR_MDIO_0
  IO51  = GND
  IO52  = KR_P0_OCP_RX_DP
  IO53  = KR_P0_OCP_RX_DN
  IO54  = GND
  IO55  = LED_GBE_P3_0
  IO56  = LED_GBE_P3_1
  IO57  = GND
  IO58  = KR_P1_OCP_RX_DP
  IO59  = KR_P1_OCP_RX_DN
  IO60  = GND
  IO61  = SMB_PCH_MEZZ_LOM2_SCL
  IO62  = SMB_PCH_MEZZ_LOM2_SDA
  IO63  = GND
  IO64  = FM_OCP_MEZZC_PRES_N

(kicad_pcb
	(version 20260206)
	(generator "pcbnew")
	(generator_version "10.0")
	(general
		(thickness 1.6)
		(legacy_teardrops no)
	)
	(paper "A4")
	(title_block
		(title "Wiwynn_Tioga_Pass_MB.brd")
		(comment 1 "Tioga Pass / footprint 349 of 4770 (J8E4), pads 50-66 of 66")
	)
	(layers
		(0 "F.Cu" signal "TOP")
		(4 "In1.Cu" signal "L2GND")
		(6 "In2.Cu" signal "L3")
		(8 "In3.Cu" signal "L4GND")
		(10 "In4.Cu" signal "L5")
		(12 "In5.Cu" signal "L6GND")
		(14 "In6.Cu" signal "L7VCC")
		(16 "In7.Cu" signal "L8VCC")
		(18 "In8.Cu" signal "L9GND")
		(20 "In9.Cu" signal "L10")
		(22 "In10.Cu" signal "L11GND")
		(24 "In11.Cu" signal "L12")
		(26 "In12.Cu" signal "L13GND")
		(2 "B.Cu" signal "BOTTOM")
		(9 "F.Adhes" user "F.Adhesive")
		(11 "B.Adhes" user "B.Adhesive")
		(13 "F.Paste" user "Package Geometry/Pastemask Top")
		(15 "B.Paste" user "Package Geometry/Pastemask Bottom")
		(5 "F.SilkS" user "Ref Des/Silkscreen Top")
		(7 "B.SilkS" user "Ref Des/Silkscreen Bottom")
		(1 "F.Mask" user "Board Geometry/Soldermask Top")
		(3 "B.Mask" user "Board Geometry/Soldermask Bottom")
		(17 "Dwgs.User" user "User.Drawings")
		(19 "Cmts.User" user "User.Comments")
		(21 "Eco1.User" user "User.Eco1")
		(23 "Eco2.User" user "User.Eco2")
		(25 "Edge.Cuts" user "Board Geometry/Outline")
		(27 "Margin" user)
		(31 "F.CrtYd" user "Package Geometry/Place Bound Top")
		(29 "B.CrtYd" user "Package Geometry/Place Bound Bottom")
		(35 "F.Fab" user "Ref Des/Assembly Top")
		(33 "B.Fab" user "Ref Des/Assembly Bottom")
	)
	(footprint ""
		(layer "F.Cu")
		(at 440.550046 -57.596024 90)
		(property "Reference" "J8E4"
			(at 1.795272 -4.825746 90)
			(unlocked yes)
			(layer "F.SilkS")
			(effects
				(font
					(size 0.7874 0.5842)
					(thickness 0.1524)
				)
			)
		)
		(property "Value" ""
			(at 0 0 90)
			(layer "F.Fab")
			(effects
				(font
					(size 1.27 1.27)
				)
			)
		)
		(duplicate_pad_numbers_are_jumpers no)
		(pad "48" smd rect
			(at 4.406646 11.999976 90)
			(size 2.0066 0.508)
			(layers "F.Cu" "F.Mask" "F.Paste")
			(net "GND")
		)
		(pad "49" smd rect
			(at 4.406646 12.800076 90)
			(size 2.0066 0.508)
			(layers "F.Cu" "F.Mask" "F.Paste")
			(net "TP_SHARED_KR_MDC_0")
		)
		(pad "50" smd rect
			(at 4.406646 13.599922 90)
			(size 2.0066 0.508)
			(layers "F.Cu" "F.Mask" "F.Paste")
			(net "TP_SHARED_KR_MDIO_0")
		)
		(pad "51" smd rect
			(at 4.406646 14.400022 90)
			(size 2.0066 0.508)
			(layers "F.Cu" "F.Mask" "F.Paste")
			(net "GND")
		)
		(pad "52" smd rect
			(at 4.406646 15.200122 90)
			(size 2.0066 0.508)
			(layers "F.Cu" "F.Mask" "F.Paste")
			(net "KR_P0_OCP_RX_DP")
		)
		(pad "53" smd rect
			(at 4.406646 15.999968 90)
			(size 2.0066 0.508)
			(layers "F.Cu" "F.Mask" "F.Paste")
			(net "KR_P0_OCP_RX_DN")
		)
		(pad "54" smd rect
			(at 4.406646 16.800068 90)
			(size 2.0066 0.508)
			(layers "F.Cu" "F.Mask" "F.Paste")
			(net "GND")
		)
		(pad "55" smd rect
			(at 4.406646 17.599914 90)
			(size 2.0066 0.508)
			(layers "F.Cu" "F.Mask" "F.Paste")
			(net "LED_GBE_P3_0")
		)
		(pad "56" smd rect
			(at 4.406646 18.400014 90)
			(size 2.0066 0.508)
			(layers "F.Cu" "F.Mask" "F.Paste")
			(net "LED_GBE_P3_1")
		)
		(pad "57" smd rect
			(at 4.406646 19.200114 90)
			(size 2.0066 0.508)
			(layers "F.Cu" "F.Mask" "F.Paste")
			(net "GND")
		)
		(pad "58" smd rect
			(at 4.406646 19.99996 90)
			(size 2.0066 0.508)
			(layers "F.Cu" "F.Mask" "F.Paste")
			(net "KR_P1_OCP_RX_DP")
		)
		(pad "59" smd rect
			(at 4.406646 20.80006 90)
			(size 2.0066 0.508)
			(layers "F.Cu" "F.Mask" "F.Paste")
			(net "KR_P1_OCP_RX_DN")
		)
		(pad "60" smd rect
			(at 4.406646 21.599906 90)
			(size 2.0066 0.508)
			(layers "F.Cu" "F.Mask" "F.Paste")
			(net "GND")
		)
		(pad "61" smd rect
			(at 4.406646 22.400006 90)
			(size 2.0066 0.508)
			(layers "F.Cu" "F.Mask" "F.Paste")
			(net "SMB_PCH_MEZZ_LOM2_SCL")
		)
		(pad "62" smd rect
			(at 4.406646 23.200106 90)
			(size 2.0066 0.508)
			(layers "F.Cu" "F.Mask" "F.Paste")
			(net "SMB_PCH_MEZZ_LOM2_SDA")
		)
		(pad "63" smd rect
			(at 4.406646 23.999952 90)
			(size 2.0066 0.508)
			(layers "F.Cu" "F.Mask" "F.Paste")
			(net "GND")
		)
		(pad "64" smd rect
			(at 4.406646 24.800052 90)
			(size 2.0066 0.508)
			(layers "F.Cu" "F.Mask" "F.Paste")
			(net "FM_OCP_MEZZC_PRES_N")
		)
	)
)
